FILE_TYPE = CONNECTIVITY;
{Allegro Design Entry HDL 17.4-2019 S026 (4007227) 1/17/2022}
"PAGE_NUMBER" = 156;
0"NC";
1"GND\g";
2"GND\g";
3"GND\g";
4"GND\g";
5"GND\g";
6"GND\g";
7"GND\g";
8"P3V3_AUX\g";
9"GND\g";
10"P1V5_BAT_IN";
11"P3V_BAT";
12"P3V_BAT_R";
13"P3V3_RTC_AUX\g";
14"GND\g";
15"P1V5_BAT\g";
16"GND\g";
17"P3V3_STBY_R";
18"P1V5_BAT_OUT_R"CDS_PHYS_NET_NAME"P1V5_BAT_OUT_R";
19"BAT_LDO_EN";
20"P3V3_RTC_AUX_R";
21"CLR_CMOS_N";
22"P1V5_BAT_OUT";
23"BAT_LDO_EN";
24"P1V5_BAT_IN";
25"P1V5_BAT_OUT";
26"U9_NR";
27"CLR_CMOS";
28"GND\g";
29"GND\g";
%"Q_RES"
"2","(-6550,7275)","0","pure_quanta","I100";
;
LOCATION"R5052"
$SEC"1"
CDS_SEC"1"
WATTAGE"1/16W"
TOLERANCE"5%"
VALUE"0"
PACK_TYPE"0402LF"
MATERIAL"CHIP"
CDS_LIB"pure_quanta"
PART_NUMBER"CS00002JB13";
"A"
$PN"1"20;
"B"
$PN"2"13;
%"Q_RES"
"1","(-6325,7000)","0","pure_quanta","I101";
;
LOCATION"R5051"
$SEC"1"
CDS_SEC"1"
MATERIAL"EMPTY"
WATTAGE"1/16W"
VALUE"0"
TOLERANCE"5%"
PACK_TYPE"0402LF"
CDS_LIB"pure_quanta"
PART_NUMBER"CS00002JB13";
"B"
$PN"2"10;
"A"
$PN"1"13;
%"UNIVERSAL_POWER"
"1","(-6850,7850)","0","pure_quanta_power","I102";
;
HDL_POWER"P3V3_RTC_AUX"
CDS_LIB"pure_quanta_power";
"A"13;
%"UNIVERSAL_GND"
"1","(-5650,5075)","5","pure_quanta_power","I103";
;
CDS_LIB"pure_quanta_power"
HDL_POWER"GND";
"A"29;
%"MOSFET_DUAL_6P"
"1","(-5300,5025)","0","pure_quanta","I104";
;
LOCATION"Q8"
$SEC"1"
CDS_SEC"1"
VALUE"2N7002KDW"
PART_TYPE"SMLF"
MATERIAL"IC"
CDS_LMAN_SYM_OUTLINE"-150,100,150,-100"
NEEDS_NO_SIZE"TRUE"
CDS_LIB"pure_quanta"
PART_NUMBER"BAM70020047";
"D2"
$PN"3"19;
"D1"
$PN"6"21;
"S2"
$PN"4"28;
"S1"
$PN"1"29;
"G2"
$PN"5"27;
"G1"
$PN"2"27;
%"UNIVERSAL_GND"
"1","(-4950,5075)","1","pure_quanta_power","I105";
;
CDS_LIB"pure_quanta_power"
HDL_POWER"GND";
"A"28;
%"UNIVERSAL_GND"
"1","(-5425,6300)","0","pure_quanta_power","I106";
;
CDS_LIB"pure_quanta_power"
HDL_POWER"GND";
"A"14;
%"Q_CAP"
"1","(-5425,6775)","2","pure_quanta","I107";
;
LOCATION"C45"
$SEC"1"
CDS_SEC"1"
PACK_TYPE"C0402"
VALUE"1UF"
VOLTAGE"25V"
TOLERANCE"10%"
MATERIAL"X6S"
CDS_LIB"pure_quanta"
PART_NUMBER"CH5104KEB02";
"B"
$PN"2"14;
"A"
$PN"1"10;
%"Q_CAP"
"1","(-5250,6800)","2","pure_quanta","I108";
;
LOCATION"C193"
$SEC"1"
CDS_SEC"1"
PACK_TYPE"C0402"
VALUE"100NF"
VOLTAGE"50V"
TOLERANCE"10%"
MATERIAL"X7R"
CDS_LIB"pure_quanta"
PART_NUMBER"CH4106K1B01";
"B"
$PN"2"14;
"A"
$PN"1"10;
%"UNIVERSAL_GND"
"1","(-4675,6600)","0","pure_quanta_power","I110";
;
CDS_LIB"pure_quanta_power"
HDL_POWER"GND";
"A"1;
%"UNIVERSAL_GND"
"1","(-3250,3050)","0","pure_quanta_power","I112";
;
CDS_LIB"pure_quanta_power"
HDL_POWER"GND";
"A"2;
%"Q_CAP"
"1","(-3250,3375)","0","pure_quanta","I113";
;
LOCATION"C22"
$SEC"1"
CDS_SEC"1"
VOLTAGE"50V"
MATERIAL"EMPTY"
TOLERANCE"10%"
PACK_TYPE"C0402"
VALUE"0.01UF"
CDS_LIB"pure_quanta"
PART_NUMBER"CH31006KB18";
"B"
$PN"2"2;
"A"
$PN"1"26;
%"Q_RES"
"1","(-2975,5700)","0","pure_quanta","I116";
;
LOCATION"R1779"
$SEC"1"
CDS_SEC"1"
TOLERANCE"1%"
MATERIAL"CHIP"
VALUE"100"
WATTAGE"1/16W"
PACK_TYPE"0402LF"
CDS_LIB"pure_quanta"
PART_NUMBER"CS11002FB07";
"B"
$PN"2"15;
"A"
$PN"1"21;
%"UNIVERSAL_GND"
"1","(-3575,6400)","0","pure_quanta_power","I117";
;
CDS_LIB"pure_quanta_power"
HDL_POWER"GND";
"A"3;
%"Q_CAP"
"1","(-3575,6775)","0","pure_quanta","I118";
;
LOCATION"C1564"
$SEC"1"
CDS_SEC"1"
VALUE"1UF"
PACK_TYPE"C0402"
TOLERANCE"10%"
MATERIAL"X6S"
VOLTAGE"25V"
CDS_LIB"pure_quanta"
PART_NUMBER"CH5104KEB02";
"B"
$PN"2"3;
"A"
$PN"1"22;
%"Q_RES"
"1","(-3075,7000)","0","pure_quanta","I120";
;
LOCATION"R5053"
$SEC"1"
CDS_SEC"1"
MATERIAL"EMPTY"
TOLERANCE"1%"
PACK_TYPE"0402LF"
WATTAGE"1/16W"
VALUE"1K"
CDS_LIB"pure_quanta"
PART_NUMBER"CS21002FB06";
"B"
$PN"2"18;
"A"
$PN"1"22;
%"UNIVERSAL_POWER"
"1","(-2300,6800)","0","pure_quanta_power","I121";
;
HDL_POWER"P1V5_BAT"
CDS_LIB"pure_quanta_power";
"A"15;
%"Q_RES"
"2","(-2750,7525)","0","pure_quanta","I122";
;
LOCATION"R5054"
$SEC"1"
CDS_SEC"1"
TOLERANCE"5%"
VALUE"0"
PACK_TYPE"0402LF"
MATERIAL"CHIP"
WATTAGE"1/16W"
CDS_LIB"pure_quanta"
PART_NUMBER"CS00002JB13";
"A"
$PN"1"20;
"B"
$PN"2"18;
%"UNIVERSAL_GND"
"1","(-2075,5925)","0","pure_quanta_power","I123";
;
CDS_LIB"pure_quanta_power"
HDL_POWER"GND";
"A"4;
%"UNIVERSAL_GND"
"1","(-1650,5925)","0","pure_quanta_power","I124";
;
CDS_LIB"pure_quanta_power"
HDL_POWER"GND";
"A"5;
%"Q_CAP"
"1","(-2075,6275)","0","pure_quanta","I125";
;
LOCATION"C1567"
$SEC"1"
CDS_SEC"1"
VALUE"1UF"
MATERIAL"X6S"
TOLERANCE"10%"
VOLTAGE"25V"
PACK_TYPE"C0402"
CDS_LIB"pure_quanta"
PART_NUMBER"CH5104KEB02";
"B"
$PN"2"4;
"A"
$PN"1"15;
%"Q_CAP"
"1","(-1650,6275)","0","pure_quanta","I126";
;
LOCATION"C5032"
$SEC"1"
CDS_SEC"1"
PACK_TYPE"C0805"
VALUE"10UF"
VOLTAGE"25V"
TOLERANCE"10%"
MATERIAL"X6S"
CDS_LIB"pure_quanta"
PART_NUMBER"CH6104KEA00";
"B"
$PN"2"5;
"A"
$PN"1"15;
%"UNIVERSAL_GND"
"1","(-1900,7325)","2","pure_quanta_power","I127";
;
CDS_LIB"pure_quanta_power"
HDL_POWER"GND";
"A"6;
%"CONN3_210HP1030BR1"
"1","(-1600,7600)","0","pure_quanta","I128";
;
LOCATION"JP12"
$SEC"1"
CDS_SEC"1"
MATERIAL"IO"
VALUE"CONN3_210-HP1-030BR1"
PART_TYPE"THLF"
CDS_LMAN_SYM_OUTLINE"-50,100,50,-100"
NEEDS_NO_SIZE"TRUE"
CDS_LIB"pure_quanta"
PART_NUMBER"DFHD03MS213";
"1"
$PN"1"18;
"2"
$PN"2"15;
"3"
$PN"3"6;
%"Q_RES"
"2","(-4825,6350)","0","pure_quanta","I129";
;
LOCATION"R1777"
$SEC"1"
CDS_SEC"1"
WATTAGE"1/16W"
TOLERANCE"1%"
VALUE"1K"
MATERIAL"CHIP"
PACK_TYPE"0402LF"
CDS_LIB"pure_quanta"
PART_NUMBER"CS21002FB06";
"A"
$PN"1"10;
"B"
$PN"2"19;
%"NCP698SQ15T1G"
"1","(-4300,6925)","0","pure_quanta","I130";
;
LOCATION"U167"
$SEC"1"
CDS_SEC"1"
MATERIAL"EMPTY"
VALUE"NCP698SQ15T1G"
PART_TYPE"SMLF"
CDS_LMAN_SYM_OUTLINE"-200,125,200,-125"
NEEDS_NO_SIZE"TRUE"
CDS_LIB"pure_quanta"
PART_NUMBER"AL000698000";
"EN"
$PN"4"19;
"VIN"
$PN"2"10;
"VOUT"
$PN"3"22;
"GND"
$PN"1"1;
%"Q_RES"
"1","(-8175,6950)","0","pure_quanta","I131";
;
LOCATION"R1775"
$SEC"1"
CDS_SEC"1"
VALUE"1K"
PACK_TYPE"0402LF"
WATTAGE"1/16W"
TOLERANCE"1%"
MATERIAL"CHIP"
CDS_LIB"pure_quanta"
PART_NUMBER"CS21002FB06";
"B"
$PN"2"12;
"A"
$PN"1"11;
%"GND"
"1","(-9400,6450)","0","pure_quanta_power","I85";
;
SIZE"1B"
CDS_LIB"pure_quanta_power"
HDL_POWER"GND";
"A<SIZE-1..0>\NAC"7;
%"CONN2_AAABAT029Y19"
"1","(-9125,6950)","2","pure_quanta","I86";
;
LOCATION"BT2"
$SEC"1"
CDS_SEC"1"
VALUE"CONN2_AAA-BAT-029-Y19"
MATERIAL"IO"
PART_TYPE"THLF"
CDS_LMAN_SYM_OUTLINE"-50,50,50,-50"
NEEDS_NO_SIZE"TRUE"
CDS_LIB"pure_quanta"
PART_NUMBER"DFHS02FR062";
"2"
$PN"2"7;
"1"
$PN"1"11;
%"UNIVERSAL_POWER"
"1","(-8525,7400)","0","pure_quanta_power","I87";
;
HDL_POWER"P3V3_AUX"
CDS_LIB"pure_quanta_power";
"A"8;
%"UNIVERSAL_GND"
"1","(-5375,3450)","0","pure_quanta_power","I90";
;
CDS_LIB"pure_quanta_power"
HDL_POWER"GND";
"A"9;
%"TPS71715DCKR"
"1","(-4725,3650)","0","pure_quanta","I91";
;
LOCATION"U9"
SEC"1"
MATERIAL"EMPTY"
PART_TYPE"SMLF"
VALUE"TPS71715DCKR"
SEC_TYPE""
CDS_LMAN_SYM_OUTLINE"-250,150,250,-150"
NEEDS_NO_SIZE"TRUE"
CDS_LIB"pure_quanta"
PART_NUMBER"AL071715001";
"OUT"
$PN"5"25;
"NR||FB"
$PN"4"26;
"IN"
$PN"1"24;
"EN"
$PN"3"23;
"GND"
$PN"2"9;
%"UNIVERSAL_GND"
"1","(-6250,4350)","0","pure_quanta_power","I93";
;
CDS_LIB"pure_quanta_power"
HDL_POWER"GND";
"A"16;
%"Q_RES"
"2","(-6700,4825)","0","pure_quanta","I94";
;
LOCATION"R1776"
$SEC"1"
CDS_SEC"1"
PACK_TYPE"0402LF"
WATTAGE"1/16W"
TOLERANCE"1%"
MATERIAL"CHIP"
VALUE"1K"
CDS_LIB"pure_quanta"
BOM_COST"VR_SYSTEM "
PART_NUMBER"CS21002FB06";
"A"
$PN"1"27;
"B"
$PN"2"16;
%"Q_CAP"
"1","(-6250,4825)","0","pure_quanta","I95";
;
LOCATION"C1563"
$SEC"1"
CDS_SEC"1"
TOLERANCE"10%"
VOLTAGE"16V"
MATERIAL"X7R"
VALUE"0.1UF"
PACK_TYPE"C0402"
CDS_LIB"pure_quanta"
PART_NUMBER"CH4103K1B08";
"B"
$PN"2"16;
"A"
$PN"1"27;
%"Q_RES"
"1","(-8175,7050)","0","pure_quanta","I97";
;
LOCATION"R5101"
$SEC"1"
CDS_SEC"1"
PACK_TYPE"0402LF"
MATERIAL"CHIP"
WATTAGE"1/16W"
TOLERANCE"5%"
VALUE"10K"
CDS_LIB"pure_quanta"
PART_NUMBER"CS31002JB08";
"B"
$PN"2"17;
"A"
$PN"1"8;
%"SCHOTTKY_DUAL_12A_3C"
"1","(-7200,7000)","5","pure_quanta","I99";
;
LOCATION"U166"
$SEC"1"
CDS_SEC"1"
MATERIAL"IC"
VALUE"BAT54CW"
PART_TYPE"SMLF"
CDS_LIB"pure_quanta"
NEEDS_NO_SIZE"TRUE"
CDS_LMAN_SYM_OUTLINE"-100,50,100,-50"
PART_NUMBER"BCBAT54CZ13";
"C"
$PN"3"13;
"B"
$PN"1"17;
"A"
$PN"2"12;
END.
